# T6G (Grand Teton) — schematic netlist excerpt (pin names and nets, part order shuffled) for the footprints in the layout excerpt that follows; sources: Cadence DE-HDL packaged netlist, KiCad conversion of 04192023_DAF0TMB3IC0_F0TG_MB_C_brd_V02_OCP.brd

J76  PICOPROBE_BXA  DELTA-L 4.0 EMPTY  pkg TRIANG_LAUNCH_3PXB  page 229
  \1_p\  = DELTA_L_85_10INCH_BOT_DP
  \2_n\  = DELTA_L_85_10INCH_BOT_DN
  \3_g\  = DELTA_L_GND_1

(kicad_pcb
	(version 20260206)
	(generator "pcbnew")
	(generator_version "10.0")
	(general
		(thickness 1.6)
		(legacy_teardrops no)
	)
	(paper "A4")
	(title_block
		(title "04192023_DAF0TMB3IC0_F0TG_MB_C_brd_V02_OCP.brd")
		(comment 1 "Grand Teton / footprints 8276-8276 of 8354")
	)
	(layers
		(0 "F.Cu" signal "TOP")
		(4 "In1.Cu" signal "GND")
		(6 "In2.Cu" signal "IN1")
		(8 "In3.Cu" signal "GND1")
		(10 "In4.Cu" signal "IN2")
		(12 "In5.Cu" signal "GND2")
		(14 "In6.Cu" signal "IN3")
		(16 "In7.Cu" signal "GND3")
		(18 "In8.Cu" signal "VCC")
		(20 "In9.Cu" signal "VCC1")
		(22 "In10.Cu" signal "GND4")
		(24 "In11.Cu" signal "IN4")
		(26 "In12.Cu" signal "GND5")
		(28 "In13.Cu" signal "IN5")
		(30 "In14.Cu" signal "GND6")
		(32 "In15.Cu" signal "IN6")
		(34 "In16.Cu" signal "GND7")
		(2 "B.Cu" signal "BOTTOM")
		(9 "F.Adhes" user "F.Adhesive")
		(11 "B.Adhes" user "B.Adhesive")
		(13 "F.Paste" user "Package Geometry/Pastemask Top")
		(15 "B.Paste" user "Package Geometry/Pastemask Bottom")
		(5 "F.SilkS" user "Ref Des/Silkscreen Top")
		(7 "B.SilkS" user "Ref Des/Silkscreen Bottom")
		(1 "F.Mask" user "Board Geometry/Soldermask Top")
		(3 "B.Mask" user "Board Geometry/Soldermask Bottom")
		(17 "Dwgs.User" user "User.Drawings")
		(19 "Cmts.User" user "User.Comments")
		(21 "Eco1.User" user "User.Eco1")
		(23 "Eco2.User" user "User.Eco2")
		(25 "Edge.Cuts" user "Board Geometry/Outline")
		(27 "Margin" user)
		(31 "F.CrtYd" user "Package Geometry/Place Bound Top")
		(29 "B.CrtYd" user "Package Geometry/Place Bound Bottom")
		(35 "F.Fab" user "Ref Des/Assembly Top")
		(33 "B.Fab" user "Ref Des/Assembly Bottom")
	)
	(footprint ""
		(layer "B.Cu")
		(at 212.471508 7.622794 180)
		(property "Reference" "J76"
			(at 4.59867 -1.055878 270)
			(unlocked yes)
			(layer "B.SilkS")
			(effects
				(font
					(size 0.7874 0.5842)
					(thickness 0.1524)
				)
				(justify left mirror)
			)
		)
		(property "Value" ""
			(at 0 0 0)
			(layer "B.Fab")
			(effects
				(font
					(size 1.27 1.27)
				)
				(justify mirror)
			)
		)
		(duplicate_pad_numbers_are_jumpers no)
		(fp_line
			(start 1.2192 2.06756)
			(end 1.2192 -2.06756)
			(stroke
				(width 0.1524)
				(type default)
			)
			(layer "B.SilkS")
		)
		(fp_line
			(start 1.2192 -2.06756)
			(end -1.2192 -2.06756)
			(stroke
				(width 0.1524)
				(type default)
			)
			(layer "B.SilkS")
		)
		(fp_line
			(start -1.2192 2.06756)
			(end 1.2192 2.06756)
			(stroke
				(width 0.1524)
				(type default)
			)
			(layer "B.SilkS")
		)
		(fp_line
			(start -1.2192 -2.06756)
			(end -1.2192 2.06756)
			(stroke
				(width 0.1524)
				(type default)
			)
			(layer "B.SilkS")
		)
		(pad "" np_thru_hole circle
			(at -3.4671 -1.27 90)
			(size 1.0414 1.0414)
			(drill 1.0414)
			(layers "*.Cu" "*.Mask")
			(clearance 0.381)
			(thermal_gap 0.381)
		)
		(pad "" np_thru_hole circle
			(at -3.4671 1.27 90)
			(size 1.0414 1.0414)
			(drill 1.0414)
			(layers "*.Cu" "*.Mask")
			(clearance 0.381)
			(thermal_gap 0.381)
		)
		(pad "" np_thru_hole circle
			(at 2.8829 -1.27 90)
			(size 1.0414 1.0414)
			(drill 1.0414)
			(layers "*.Cu" "*.Mask")
			(clearance 0.381)
			(thermal_gap 0.381)
		)
		(pad "" np_thru_hole circle
			(at 2.8829 1.27 90)
			(size 1.0414 1.0414)
			(drill 1.0414)
			(layers "*.Cu" "*.Mask")
			(clearance 0.381)
			(thermal_gap 0.381)
		)
		(pad "1" smd rect
			(at -0.8255 -0.249936 90)
			(size 0.3048 0.508)
			(layers "B.Cu" "B.Mask" "B.Paste")
			(net "DELTA_L_85_10INCH_BOT_DP")
		)
		(pad "2" smd rect
			(at -0.8255 0.249936 90)
			(size 0.3048 0.508)
			(layers "B.Cu" "B.Mask" "B.Paste")
			(net "DELTA_L_85_10INCH_BOT_DN")
		)
		(pad "3" smd circle
			(at 0 0)
			(size 0 0)
			(layers "B.Cu" "B.Mask" "B.Paste")
			(net "DELTA_L_GND_1")
		)
		(zone
			(layers "F.Cu" "B.Cu" "In1.Cu" "In2.Cu" "In3.Cu" "In4.Cu" "In5.Cu" "In6.Cu"
				"In7.Cu" "In8.Cu" "In9.Cu" "In10.Cu" "In11.Cu" "In12.Cu" "In13.Cu" "In14.Cu"
				"In15.Cu" "In16.Cu"
			)
			(hatch none 0.5)
			(connect_pads
				(clearance 0)
			)
			(min_thickness 0.25)
			(keepout
				(tracks not_allowed)
				(vias allowed)
				(pads allowed)
				(copperpour not_allowed)
				(footprints allowed)
			)
			(placement
				(enabled no)
				(sheetname "")
			)
			(fill
				(thermal_gap 0.5)
				(thermal_bridge_width 0.5)
				(island_removal_mode 0)
			)
			(polygon
				(pts
					(arc
						(start 210.515708 6.352794)
						(mid 208.661508 6.352794)
						(end 210.515708 6.352794)
					)
				)
			)
		)
		(zone
			(layers "F.Cu" "B.Cu" "In1.Cu" "In2.Cu" "In3.Cu" "In4.Cu" "In5.Cu" "In6.Cu"
				"In7.Cu" "In8.Cu" "In9.Cu" "In10.Cu" "In11.Cu" "In12.Cu" "In13.Cu" "In14.Cu"
				"In15.Cu" "In16.Cu"
			)
			(hatch none 0.5)
			(connect_pads
				(clearance 0)
			)
			(min_thickness 0.25)
			(keepout
				(tracks not_allowed)
				(vias allowed)
				(pads allowed)
				(copperpour not_allowed)
				(footprints allowed)
			)
			(placement
				(enabled no)
				(sheetname "")
			)
			(fill
				(thermal_gap 0.5)
				(thermal_bridge_width 0.5)
				(island_removal_mode 0)
			)
			(polygon
				(pts
					(arc
						(start 210.515708 8.892794)
						(mid 208.661508 8.892794)
						(end 210.515708 8.892794)
					)
				)
			)
		)
		(zone
			(layers "F.Cu" "B.Cu" "In1.Cu" "In2.Cu" "In3.Cu" "In4.Cu" "In5.Cu" "In6.Cu"
				"In7.Cu" "In8.Cu" "In9.Cu" "In10.Cu" "In11.Cu" "In12.Cu" "In13.Cu" "In14.Cu"
				"In15.Cu" "In16.Cu"
			)
			(hatch none 0.5)
			(connect_pads
				(clearance 0)
			)
			(min_thickness 0.25)
			(keepout
				(tracks not_allowed)
				(vias allowed)
				(pads allowed)
				(copperpour not_allowed)
				(footprints allowed)
			)
			(placement
				(enabled no)
				(sheetname "")
			)
			(fill
				(thermal_gap 0.5)
				(thermal_bridge_width 0.5)
				(island_removal_mode 0)
			)
			(polygon
				(pts
					(arc
						(start 216.865708 6.352794)
						(mid 215.011508 6.352794)
						(end 216.865708 6.352794)
					)
				)
			)
		)
		(zone
			(layers "F.Cu" "B.Cu" "In1.Cu" "In2.Cu" "In3.Cu" "In4.Cu" "In5.Cu" "In6.Cu"
				"In7.Cu" "In8.Cu" "In9.Cu" "In10.Cu" "In11.Cu" "In12.Cu" "In13.Cu" "In14.Cu"
				"In15.Cu" "In16.Cu"
			)
			(hatch none 0.5)
			(connect_pads
				(clearance 0)
			)
			(min_thickness 0.25)
			(keepout
				(tracks not_allowed)
				(vias allowed)
				(pads allowed)
				(copperpour not_allowed)
				(footprints allowed)
			)
			(placement
				(enabled no)
				(sheetname "")
			)
			(fill
				(thermal_gap 0.5)
				(thermal_bridge_width 0.5)
				(island_removal_mode 0)
			)
			(polygon
				(pts
					(arc
						(start 216.865708 8.892794)
						(mid 215.011508 8.892794)
						(end 216.865708 8.892794)
					)
				)
			)
		)
		(zone
			(layer "B.Cu")
			(hatch none 0.5)
			(connect_pads
				(clearance 0)
			)
			(min_thickness 0.25)
			(keepout
				(tracks not_allowed)
				(vias allowed)
				(pads allowed)
				(copperpour not_allowed)
				(footprints allowed)
			)
			(placement
				(enabled no)
				(sheetname "")
			)
			(fill
				(thermal_gap 0.5)
				(thermal_bridge_width 0.5)
				(island_removal_mode 0)
			)
			(polygon
				(pts
					(xy 213.589108 8.171434) (xy 213.589108 8.07593) (xy 212.992208 8.07593) (xy 212.992208 7.66953)
					(xy 213.589108 7.66953) (xy 213.589108 7.576058) (xy 212.992208 7.576058) (xy 212.992208 7.169658)
					(xy 213.589108 7.169658) (xy 213.589108 7.074154) (xy 212.890608 7.074154) (xy 212.890608 8.171434)
				)
			)
		)
	)
)
